FILE_TYPE = CONNECTIVITY;
{Allegro Design Entry HDL 17.4-2019 S026 (4007227) 1/17/2022}
"PAGE_NUMBER" = 252;
0"NC";
1"GND\g";
2"P3V3_AUX\g";
3"GND\g";
4"GND\g";
5"GND\g";
6"GND\g";
7"SMB_PCIE0_3V3AUX_SDA_R"CDS_PHYS_NET_NAME"SMB_PCIE0_3V3AUX_SDA_R";
8"SMB_FRU_3V3AUX_SCL_R"CDS_PHYS_NET_NAME"SMB_FRU_3V3AUX_SCL_R";
9"SMB_BMC_SWB_SDA_R4"CDS_PHYS_NET_NAME"SMB_BMC_SWB_SDA_R4";
10"SMB_BMC_SWB_SDA"CDS_PHYS_NET_NAME"SMB_BMC_SWB_SDA";
11"SMB_BMC_SWB_SCL"CDS_PHYS_NET_NAME"SMB_BMC_SWB_SCL";
12"SMB_PCIE0_3V3AUX_SCL_R"CDS_PHYS_NET_NAME"SMB_PCIE0_3V3AUX_SCL_R";
13"SMB_PCIE0_3V3AUX_SCL"CDS_PHYS_NET_NAME"SMB_PCIE0_3V3AUX_SCL";
14"SMB_FRU_3V3AUX_SCL"CDS_PHYS_NET_NAME"SMB_FRU_3V3AUX_SCL";
15"SMB_FRU_3V3AUX_SDA"CDS_PHYS_NET_NAME"SMB_FRU_3V3AUX_SDA";
16"SMB_FRU_3V3AUX_SDA"CDS_PHYS_NET_NAME"SMB_FRU_3V3AUX_SDA";
17"SMB_BMC_SWB_SCL_R4"CDS_PHYS_NET_NAME"SMB_BMC_SWB_SCL_R4";
18"SMB_SENSOR_E1S_3V3AUX_SDA"CDS_PHYS_NET_NAME"SMB_SENSOR_E1S_3V3AUX_SDA";
19"SMB_USB_CPU0_HUB1_SDA";
20"SMB_SENSOR_E1S_3V3AUX_SCL"CDS_PHYS_NET_NAME"SMB_SENSOR_E1S_3V3AUX_SCL";
21"SMB_SENSOR_E1S_3V3AUX_SDA"CDS_PHYS_NET_NAME"SMB_SENSOR_E1S_3V3AUX_SDA";
22"SMB_SENSOR_M2_P1_3V3AUX_SCL"CDS_PHYS_NET_NAME"SMB_SENSOR_M2_P0_3V3AUX_SCL";
23"SMB_SENSOR_E1S_3V3AUX_SCL"CDS_PHYS_NET_NAME"SMB_SENSOR_E1S_3V3AUX_SCL";
24"SMB_BMC_SWB_SDA"CDS_PHYS_NET_NAME"SMB_BMC_SWB_SDA";
25"SMB_SENSOR_M2_P1_3V3AUX_SDA"CDS_PHYS_NET_NAME"SMB_SENSOR_M2_P0_3V3AUX_SDA";
26"SMB_IOEXP_3V3AUX_SDA"CDS_PHYS_NET_NAME"SMB_IOEXP_3V3AUX_SDA";
27"SMB_IOEXP_3V3AUX_SCL"CDS_PHYS_NET_NAME"SMB_IOEXP_3V3AUX_SCL";
28"SMB_USB_CPU0_HUB1_SCL";
29"SMB_SENSOR_M2_P1_3V3AUX_SDA"CDS_PHYS_NET_NAME"SMB_SENSOR_M2_P0_3V3AUX_SDA";
30"SMB_BMC_SWB_SCL"CDS_PHYS_NET_NAME"SMB_BMC_SWB_SCL";
31"SMB_IOEXP_3V3AUX_SDA"CDS_PHYS_NET_NAME"SMB_IOEXP_3V3AUX_SDA";
32"SMB_INA230_3V3AUX_SCL"CDS_PHYS_NET_NAME"SMB_INA230_3V3AUX_SCL";
33"SMB_PCIE0_3V3AUX_SDA"CDS_PHYS_NET_NAME"SMB_PCIE0_3V3AUX_SDA";
34"SMB_IOEXP_3V3AUX_SCL"CDS_PHYS_NET_NAME"SMB_IOEXP_3V3AUX_SCL";
35"SMB_PCIE0_3V3AUX_SCL"CDS_PHYS_NET_NAME"SMB_PCIE0_3V3AUX_SCL";
36"SMB_PCIE0_3V3AUX_SDA"CDS_PHYS_NET_NAME"SMB_PCIE0_3V3AUX_SDA";
37"SMB_USB_CPU0_HUB1_SCL";
38"SMB_SENSOR_M2_P1_3V3AUX_SCL"CDS_PHYS_NET_NAME"SMB_SENSOR_M2_P0_3V3AUX_SCL";
39"PCA9548_PCIE3_ADDR2";
40"PCA9548_PCIE3_ADDR1";
41"PCA9548_PCIE3_ADDR0";
42"SMB_PCIE0_3V3AUX_SCL_R3"CDS_PHYS_NET_NAME"SMB_PCIE0_3V3AUX_SCL_R3";
43"SMB_PCIE0_3V3AUX_SDA_R5"CDS_PHYS_NET_NAME"SMB_PCIE0_3V3AUX_SDA_R5";
44"PCA9548_PCIE3_ADDR0";
45"PCA9548_PCIE3_ADDR1";
46"PCA9548_PCIE3_ADDR2"CDS_PHYS_NET_NAME"PCA9548_PCIE3_ADDR2";
47"PU_RST_SMB_PCIE0_N"CDS_PHYS_NET_NAME"PU_RST_SMB_PCIE0_N";
48"SMB_USB_CPU0_HUB1_SDA_R";
49"SMB_USB_CPU0_HUB1_SCL_R";
50"SMB_IOEXP_3V3AUX_SDA_R"CDS_PHYS_NET_NAME"SMB_IOEXP_3V3AUX_SDA_R";
51"SMB_IOEXP_3V3AUX_SCL_R"CDS_PHYS_NET_NAME"SMB_IOEXP_3V3AUX_SCL_R";
52"SMB_PCIE0_3V3AUX_SDA_R3"CDS_PHYS_NET_NAME"SMB_PCIE0_3V3AUX_SDA_R3";
53"SMB_PCIE0_3V3AUX_SCL_R5"CDS_PHYS_NET_NAME"SMB_PCIE0_3V3AUX_SCL_R5";
54"SMB_USB_CPU0_HUB1_SDA";
55"RST_SMB_SWITCH_N"CDS_PHYS_NET_NAME"RST_SMB_SWITCH_N";
56"SMB_FRU_3V3AUX_SCL"CDS_PHYS_NET_NAME"SMB_FRU_3V3AUX_SCL";
57"SMB_INA230_3V3AUX_SCL"CDS_PHYS_NET_NAME"SMB_INA230_3V3AUX_SCL";
58"SMB_INA230_3V3AUX_SDA"CDS_PHYS_NET_NAME"SMB_INA230_3V3AUX_SDA";
59"SMB_INA230_3V3AUX_SDA"CDS_PHYS_NET_NAME"SMB_INA230_3V3AUX_SDA";
60"SMB_FRU_3V3AUX_SDA_R"CDS_PHYS_NET_NAME"SMB_FRU_3V3AUX_SDA_R";
61"SMB_INA230_3V3AUX_SDA_R"CDS_PHYS_NET_NAME"SMB_INA230_3V3AUX_SDA_R";
62"P3V3_AUX\g";
63"P3V3_AUX\g";
64"P3V3_AUX\g";
65"SMB_INA230_3V3AUX_SCL_R"CDS_PHYS_NET_NAME"SMB_INA230_3V3AUX_SCL_R";
%"UNIVERSAL_GND"
"1","(-5900,2100)","0","pure_quanta_power","I1";
;
ROOM"IO_SLOT"
CDS_LIB"pure_quanta_power"
HDL_POWER"GND";
"A"1;
%"Q_RES"
"2","(-5350,2975)","0","pure_quanta","I10";
;
LOCATION"R320"
$SEC"1"
CDS_SEC"1"
VALUE"10K"
TOLERANCE"1%"
PACK_TYPE"0402LF"
WATTAGE"1/16W"
MATERIAL"EMPTY"
CDS_LIB"pure_quanta"
PART_NUMBER"CS31002FB08";
"A"
$PN"1"64;
"B"
$PN"2"41;
%"Q_RES"
"2","(-5900,2325)","0","pure_quanta","I2";
;
LOCATION"R317"
$SEC"1"
CDS_SEC"1"
TOLERANCE"1%"
WATTAGE"1/16W"
MATERIAL"CHIP"
PACK_TYPE"0402LF"
VALUE"1K"
CDS_LIB"pure_quanta"
PART_NUMBER"CS21002FB06";
"A"
$PN"1"39;
"B"
$PN"2"1;
%"Q_RES"
"2","(-6600,5025)","2","pure_quanta","I21";
;
LOCATION"R1822"
$SEC"1"
CDS_SEC"1"
PACK_TYPE"0402LF"
MATERIAL"CHIP"
WATTAGE"1/16W"
TOLERANCE"1%"
VALUE"10K"
CDS_LIB"pure_quanta"
PART_NUMBER"CS31002FB08";
"A"
$PN"1"2;
"B"
$PN"2"55;
%"UNIVERSAL_POWER"
"1","(-6600,5300)","0","pure_quanta_power","I22";
;
HDL_POWER"P3V3_AUX"
CDS_LIB"pure_quanta_power";
"A"2;
%"Q_RES"
"1","(-5400,4225)","2","pure_quanta","I23";
;
LOCATION"R3526"
$SEC"1"
CDS_SEC"1"
TOLERANCE"5%"
VALUE"0"
MATERIAL"CHIP"
PACK_TYPE"0402LF"
WATTAGE"1/16W"
CDS_LIB"pure_quanta"
PART_NUMBER"CS00002JB13";
"B"
$PN"2"23;
"A"
$PN"1"53;
%"Q_RES"
"1","(-5400,4275)","2","pure_quanta","I24";
;
LOCATION"R3527"
$SEC"1"
CDS_SEC"1"
TOLERANCE"5%"
VALUE"0"
MATERIAL"CHIP"
CDS_LIB"pure_quanta"
PACK_TYPE"0402LF"
WATTAGE"1/16W"
PART_NUMBER"CS00002JB13";
"B"
$PN"2"21;
"A"
$PN"1"43;
%"Q_RES"
"1","(-5400,4325)","2","pure_quanta","I25";
;
LOCATION"R2967"
$SEC"1"
CDS_SEC"1"
VALUE"0"
TOLERANCE"5%"
MATERIAL"CHIP"
PACK_TYPE"0402LF"
WATTAGE"1/16W"
CDS_LIB"pure_quanta"
PART_NUMBER"CS00002JB13";
"B"
$PN"2"22;
"A"
$PN"1"42;
%"Q_RES"
"1","(-5400,4375)","2","pure_quanta","I26";
;
LOCATION"R2968"
$SEC"1"
CDS_SEC"1"
TOLERANCE"5%"
VALUE"0"
MATERIAL"CHIP"
WATTAGE"1/16W"
PACK_TYPE"0402LF"
CDS_LIB"pure_quanta"
PART_NUMBER"CS00002JB13";
"B"
$PN"2"25;
"A"
$PN"1"52;
%"Q_RES"
"1","(-5400,4425)","2","pure_quanta","I27";
;
LOCATION"R3393"
SEC"1"
TOLERANCE"5%"
VALUE"0"
MATERIAL"CHIP"
CDS_LIB"pure_quanta"
SEC_TYPE"0402LF"
WATTAGE"1/16W"
PACK_TYPE"0402LF"
PART_NUMBER"CS00002JB13";
"B"
$PN"2"27;
"A"
$PN"1"51;
%"Q_RES"
"1","(-5500,4675)","0","pure_quanta","I28";
;
LOCATION"R2268"
$SEC"1"
CDS_SEC"1"
TOLERANCE"5%"
VALUE"0"
MATERIAL"CHIP"
PACK_TYPE"0402LF"
WATTAGE"1/16W"
CDS_LIB"pure_quanta"
PART_NUMBER"CS00002JB13";
"B"
$PN"2"47;
"A"
$PN"1"55;
%"Q_RES"
"1","(-5400,4475)","2","pure_quanta","I29";
;
LOCATION"R3394"
$SEC"1"
CDS_SEC"1"
TOLERANCE"5%"
VALUE"0"
MATERIAL"CHIP"
CDS_LIB"pure_quanta"
WATTAGE"1/16W"
PACK_TYPE"0402LF"
PART_NUMBER"CS00002JB13";
"B"
$PN"2"26;
"A"
$PN"1"50;
%"UNIVERSAL_GND"
"1","(-5625,2100)","0","pure_quanta_power","I3";
;
ROOM"IO_SLOT"
CDS_LIB"pure_quanta_power"
HDL_POWER"GND";
"A"3;
%"TCA9548APWR"
"1","(-3925,4550)","0","pure_quanta","I33";
;
LOCATION"U36"
SEC"1"
PART_TYPE"SMLF"
VALUE"TCA9548APWR"
MATERIAL"IC"
CDS_LIB"pure_quanta"
CDS_LMAN_SYM_OUTLINE"-200,475,200,-475"
SEC_TYPE""
NEEDS_NO_SIZE"TRUE"
PART_NUMBER"AL009548K02";
"SD4"
$PN"13"9;
"SC4"
$PN"14"17;
"SD5"
$PN"15"60;
"SC5"
$PN"16"8;
"SD6"
$PN"17"61;
"SC6"
$PN"18"65;
"SD7"
$PN"19"0;
"SC7"
$PN"20"0;
"A2"
$PN"21"46;
"SCL"
$PN"22"12;
"SDA"
$PN"23"7;
"VCC"
$PN"24"62;
"GND"
$PN"12"6;
"SC3"
$PN"11"53;
"SD3"
$PN"10"43;
"SC2"
$PN"9"42;
"SD2"
$PN"8"52;
"SC1"
$PN"7"51;
"SD1"
$PN"6"50;
"SC0"
$PN"5"49;
"SD0"
$PN"4"48;
"RESET# \B"
$PN"3"47;
"A1"
$PN"2"45;
"A0"
$PN"1"44;
%"Q_CAP"
"1","(-4800,5300)","0","pure_quanta","I34";
;
LOCATION"C106"
$SEC"1"
CDS_SEC"1"
VALUE"0.1UF"
MATERIAL"X7R"
PACK_TYPE"0402"
VOLTAGE"25V"
TOLERANCE"10%"
CDS_LIB"pure_quanta"
PART_NUMBER"CH4104K1B00";
"B"
$PN"2"4;
"A"
$PN"1"62;
%"UNIVERSAL_GND"
"1","(-4800,5075)","0","pure_quanta_power","I35";
;
CDS_LIB"pure_quanta_power"
HDL_POWER"GND";
"A"4;
%"UNIVERSAL_POWER"
"1","(-4800,5625)","0","pure_quanta_power","I36";
;
HDL_POWER"P3V3_AUX"
CDS_LIB"pure_quanta_power";
"A"62;
%"Q_RES"
"1","(-2125,575)","0","pure_quanta","I37";
;
LOCATION"R1089"
$SEC"1"
CDS_SEC"1"
PACK_TYPE"0402LF"
MATERIAL"CHIP"
TOLERANCE"5%"
VALUE"2.2K"
WATTAGE"1/16W"
CDS_LIB"pure_quanta"
PART_NUMBER"CS22202JB07";
"B"
$PN"2"38;
"A"
$PN"1"63;
%"Q_RES"
"1","(-2125,525)","0","pure_quanta","I38";
;
LOCATION"R1090"
$SEC"1"
CDS_SEC"1"
TOLERANCE"5%"
VALUE"2.2K"
MATERIAL"CHIP"
CDS_LIB"pure_quanta"
PACK_TYPE"0402LF"
WATTAGE"1/16W"
PART_NUMBER"CS22202JB07";
"B"
$PN"2"29;
"A"
$PN"1"63;
%"Q_RES"
"1","(-2125,850)","0","pure_quanta","I39";
;
LOCATION"R67"
$SEC"1"
CDS_SEC"1"
MATERIAL"CHIP"
VALUE"2.2K"
TOLERANCE"5%"
WATTAGE"1/16W"
PACK_TYPE"0402LF"
CDS_LIB"pure_quanta"
PART_NUMBER"CS22202JB07";
"B"
$PN"2"16;
"A"
$PN"1"63;
%"Q_RES"
"2","(-5625,2325)","0","pure_quanta","I4";
;
LOCATION"R319"
$SEC"1"
CDS_SEC"1"
TOLERANCE"1%"
WATTAGE"1/16W"
MATERIAL"CHIP"
VALUE"1K"
PACK_TYPE"0402LF"
CDS_LIB"pure_quanta"
PART_NUMBER"CS21002FB06";
"A"
$PN"1"40;
"B"
$PN"2"3;
%"Q_RES"
"1","(-2125,900)","0","pure_quanta","I40";
;
LOCATION"R66"
$SEC"1"
CDS_SEC"1"
MATERIAL"CHIP"
PACK_TYPE"0402LF"
TOLERANCE"5%"
VALUE"2.2K"
WATTAGE"1/16W"
CDS_LIB"pure_quanta"
PART_NUMBER"CS22202JB07";
"B"
$PN"2"14;
"A"
$PN"1"63;
%"Q_RES"
"1","(-2125,1225)","0","pure_quanta","I41";
;
LOCATION"R2984"
$SEC"1"
CDS_SEC"1"
MATERIAL"CHIP"
TOLERANCE"5%"
VALUE"2.2K"
PACK_TYPE"0402LF"
WATTAGE"1/16W"
CDS_LIB"pure_quanta"
PART_NUMBER"CS22202JB07";
"B"
$PN"2"30;
"A"
$PN"1"63;
%"Q_RES"
"1","(-2125,1175)","0","pure_quanta","I42";
;
LOCATION"R2985"
$SEC"1"
CDS_SEC"1"
TOLERANCE"5%"
MATERIAL"CHIP"
VALUE"2.2K"
CDS_LIB"pure_quanta"
PACK_TYPE"0402LF"
WATTAGE"1/16W"
PART_NUMBER"CS22202JB07";
"B"
$PN"2"24;
"A"
$PN"1"63;
%"Q_RES"
"1","(-2125,1825)","0","pure_quanta","I43";
;
LOCATION"R3536"
$SEC"1"
CDS_SEC"1"
VALUE"2.2K"
TOLERANCE"5%"
MATERIAL"CHIP"
CDS_LIB"pure_quanta"
PACK_TYPE"0402LF"
WATTAGE"1/16W"
PART_NUMBER"CS22202JB07";
"B"
$PN"2"18;
"A"
$PN"1"63;
%"Q_RES"
"1","(-2125,1875)","0","pure_quanta","I44";
;
LOCATION"R3535"
$SEC"1"
CDS_SEC"1"
VALUE"2.2K"
TOLERANCE"5%"
PACK_TYPE"0402LF"
WATTAGE"1/16W"
MATERIAL"CHIP"
CDS_LIB"pure_quanta"
PART_NUMBER"CS22202JB07";
"B"
$PN"2"20;
"A"
$PN"1"63;
%"Q_RES"
"1","(-2150,2125)","0","pure_quanta","I45";
;
LOCATION"R3583"
$SEC"1"
CDS_SEC"1"
MATERIAL"CHIP"
VALUE"2.2K"
TOLERANCE"5%"
WATTAGE"1/16W"
PACK_TYPE"0402LF"
CDS_LIB"pure_quanta"
PART_NUMBER"CS22202JB07";
"B"
$PN"2"31;
"A"
$PN"1"63;
%"Q_RES"
"1","(-2150,2175)","0","pure_quanta","I46";
;
LOCATION"R3582"
$SEC"1"
CDS_SEC"1"
PACK_TYPE"0402LF"
MATERIAL"CHIP"
TOLERANCE"5%"
WATTAGE"1/16W"
VALUE"2.2K"
CDS_LIB"pure_quanta"
PART_NUMBER"CS22202JB07";
"B"
$PN"2"34;
"A"
$PN"1"63;
%"Q_RES"
"1","(-2150,2450)","0","pure_quanta","I47";
;
LOCATION"R3395"
$SEC"1"
CDS_SEC"1"
VALUE"2.2K"
TOLERANCE"5%"
MATERIAL"CHIP"
WATTAGE"1/16W"
PACK_TYPE"0402LF"
CDS_LIB"pure_quanta"
PART_NUMBER"CS22202JB07";
"B"
$PN"2"32;
"A"
$PN"1"63;
%"Q_RES"
"1","(-2150,2400)","0","pure_quanta","I48";
;
LOCATION"R3396"
$SEC"1"
CDS_SEC"1"
TOLERANCE"5%"
MATERIAL"CHIP"
VALUE"2.2K"
CDS_LIB"pure_quanta"
PACK_TYPE"0402LF"
WATTAGE"1/16W"
PART_NUMBER"CS22202JB07";
"B"
$PN"2"59;
"A"
$PN"1"63;
%"Q_RES"
"1","(-2150,2775)","0","pure_quanta","I49";
;
LOCATION"R2205"
$SEC"1"
CDS_SEC"1"
MATERIAL"EMPTY"
VALUE"2.2K"
TOLERANCE"5%"
WATTAGE"1/16W"
PACK_TYPE"0402LF"
CDS_LIB"pure_quanta"
PART_NUMBER"CS22202JB07";
"B"
$PN"2"33;
"A"
$PN"1"63;
%"UNIVERSAL_GND"
"1","(-5350,2100)","0","pure_quanta_power","I5";
;
ROOM"IO_SLOT"
CDS_LIB"pure_quanta_power"
HDL_POWER"GND";
"A"5;
%"Q_RES"
"1","(-2150,2825)","0","pure_quanta","I50";
;
LOCATION"R2204"
$SEC"1"
CDS_SEC"1"
MATERIAL"EMPTY"
VALUE"2.2K"
TOLERANCE"5%"
WATTAGE"1/16W"
PACK_TYPE"0402LF"
CDS_LIB"pure_quanta"
PART_NUMBER"CS22202JB07";
"B"
$PN"2"35;
"A"
$PN"1"63;
%"UNIVERSAL_POWER"
"1","(-2575,3025)","0","pure_quanta_power","I51";
;
HDL_POWER"P3V3_AUX"
CDS_LIB"pure_quanta_power";
"A"63;
%"Q_RES"
"2","(-5350,2325)","0","pure_quanta","I6";
;
LOCATION"R587"
$SEC"1"
CDS_SEC"1"
TOLERANCE"1%"
PACK_TYPE"0402LF"
VALUE"1K"
MATERIAL"CHIP"
WATTAGE"1/16W"
CDS_LIB"pure_quanta"
PART_NUMBER"CS21002FB06"
LOCATION"R587";
"A"
$PN"1"41;
"B"
$PN"2"5;
%"UNIVERSAL_GND"
"1","(-3425,3950)","0","pure_quanta_power","I66";
;
CDS_LIB"pure_quanta_power"
HDL_POWER"GND";
"A"6;
%"Q_RES"
"1","(-2600,4425)","0","pure_quanta","I67";
;
LOCATION"R2565"
$SEC"1"
CDS_SEC"1"
VALUE"0"
MATERIAL"CHIP"
TOLERANCE"5%"
CDS_LIB"pure_quanta"
WATTAGE"1/16W"
PACK_TYPE"0402LF"
PART_NUMBER"CS00002JB13";
"B"
$PN"2"56;
"A"
$PN"1"8;
%"Q_RES"
"1","(-2600,4375)","0","pure_quanta","I68";
;
LOCATION"R3581"
$SEC"1"
CDS_SEC"1"
MATERIAL"CHIP"
VALUE"0"
TOLERANCE"5%"
CDS_LIB"pure_quanta"
WATTAGE"1/16W"
PACK_TYPE"0402LF"
PART_NUMBER"CS00002JB13";
"B"
$PN"2"58;
"A"
$PN"1"61;
%"Q_RES"
"1","(-2600,4325)","0","pure_quanta","I69";
;
LOCATION"R3580"
$SEC"1"
CDS_SEC"1"
MATERIAL"CHIP"
TOLERANCE"5%"
VALUE"0"
CDS_LIB"pure_quanta"
WATTAGE"1/16W"
PACK_TYPE"0402LF"
PART_NUMBER"CS00002JB13";
"B"
$PN"2"57;
"A"
$PN"1"65;
%"Q_RES"
"2","(-5900,2975)","0","pure_quanta","I7";
;
LOCATION"R316"
$SEC"1"
CDS_SEC"1"
WATTAGE"1/16W"
VALUE"10K"
PACK_TYPE"0402LF"
TOLERANCE"1%"
MATERIAL"EMPTY"
CDS_LIB"pure_quanta"
PART_NUMBER"CS31002FB08";
"A"
$PN"1"64;
"B"
$PN"2"39;
%"Q_RES"
"1","(-2600,4575)","0","pure_quanta","I70";
;
LOCATION"R2704"
$SEC"1"
CDS_SEC"1"
VALUE"0"
TOLERANCE"5%"
MATERIAL"CHIP"
WATTAGE"1/16W"
PACK_TYPE"0402LF"
CDS_LIB"pure_quanta"
PART_NUMBER"CS00002JB13";
"B"
$PN"2"10;
"A"
$PN"1"9;
%"Q_RES"
"1","(-2600,4525)","0","pure_quanta","I71";
;
LOCATION"R2703"
$SEC"1"
CDS_SEC"1"
TOLERANCE"5%"
VALUE"0"
MATERIAL"CHIP"
CDS_LIB"pure_quanta"
WATTAGE"1/16W"
PACK_TYPE"0402LF"
PART_NUMBER"CS00002JB13";
"B"
$PN"2"11;
"A"
$PN"1"17;
%"Q_RES"
"1","(-2600,4475)","0","pure_quanta","I72";
;
LOCATION"R2566"
$SEC"1"
CDS_SEC"1"
VALUE"0"
MATERIAL"CHIP"
TOLERANCE"5%"
WATTAGE"1/16W"
PACK_TYPE"0402LF"
CDS_LIB"pure_quanta"
PART_NUMBER"CS00002JB13";
"B"
$PN"2"15;
"A"
$PN"1"60;
%"Q_RES"
"1","(-2525,4825)","2","pure_quanta","I73";
;
LOCATION"R55"
$SEC"1"
CDS_SEC"1"
VALUE"33.2"
TOLERANCE"1%"
MATERIAL"CHIP"
PACK_TYPE"0402LF"
CDS_LIB"pure_quanta"
WATTAGE"1/16W"
PART_NUMBER"CS03322FB03";
"B"
$PN"2"7;
"A"
$PN"1"36;
%"Q_RES"
"1","(-2525,4775)","2","pure_quanta","I74";
;
LOCATION"R65"
$SEC"1"
CDS_SEC"1"
MATERIAL"CHIP"
TOLERANCE"1%"
PACK_TYPE"0402LF"
WATTAGE"1/16W"
VALUE"33.2"
CDS_LIB"pure_quanta"
PART_NUMBER"CS03322FB03";
"B"
$PN"2"12;
"A"
$PN"1"13;
%"Q_RES"
"2","(-5625,2975)","0","pure_quanta","I8";
;
LOCATION"R318"
$SEC"1"
CDS_SEC"1"
VALUE"10K"
WATTAGE"1/16W"
PACK_TYPE"0402LF"
TOLERANCE"1%"
MATERIAL"EMPTY"
CDS_LIB"pure_quanta"
PART_NUMBER"CS31002FB08";
"A"
$PN"1"64;
"B"
$PN"2"40;
%"Q_RES"
"1","(-5400,4575)","2","pure_quanta","I83";
;
LOCATION"R6200"
$SEC"1"
CDS_SEC"1"
VALUE"0"
TOLERANCE"5%"
MATERIAL"CHIP"
PACK_TYPE"0402LF"
WATTAGE"1/16W"
CDS_LIB"pure_quanta"
PART_NUMBER"CS00002JB13";
"B"
$PN"2"54;
"A"
$PN"1"48;
%"Q_RES"
"1","(-5400,4525)","2","pure_quanta","I84";
;
LOCATION"R6201"
$SEC"1"
CDS_SEC"1"
VALUE"0"
TOLERANCE"5%"
MATERIAL"CHIP"
PACK_TYPE"0402LF"
WATTAGE"1/16W"
CDS_LIB"pure_quanta"
PART_NUMBER"CS00002JB13";
"B"
$PN"2"28;
"A"
$PN"1"49;
%"Q_RES"
"1","(-2125,1600)","0","pure_quanta","I89";
;
LOCATION"R6211"
$SEC"1"
CDS_SEC"1"
MATERIAL"CHIP"
TOLERANCE"5%"
VALUE"2.2K"
PACK_TYPE"0402LF"
WATTAGE"1/16W"
CDS_LIB"pure_quanta"
PART_NUMBER"CS22202JB07";
"B"
$PN"2"37;
"A"
$PN"1"63;
%"UNIVERSAL_POWER"
"1","(-5900,3350)","0","pure_quanta_power","I9";
;
HDL_POWER"P3V3_AUX"
CDS_LIB"pure_quanta_power";
"A"64;
%"Q_RES"
"1","(-2125,1550)","0","pure_quanta","I90";
;
LOCATION"R6212"
$SEC"1"
CDS_SEC"1"
MATERIAL"CHIP"
TOLERANCE"5%"
VALUE"2.2K"
WATTAGE"1/16W"
PACK_TYPE"0402LF"
CDS_LIB"pure_quanta"
PART_NUMBER"CS22202JB07";
"B"
$PN"2"19;
"A"
$PN"1"63;
END.
